(kicad_pcb
	(version 20260206)
	(generator "pcbnew")
	(generator_version "10.0")
	(general
		(thickness 1.6)
		(legacy_teardrops no)
	)
	(paper "A4")
	(title_block
		(title "fcb — Lightning_FCB_BRD.brd")
		(comment 1 "Lightning (Wiwynn / Facebook NVMe JBOF) / footprints 328-335 of 495")
	)
	(layers
		(0 "F.Cu" signal "TOP")
		(4 "In1.Cu" signal "L2GND")
		(6 "In2.Cu" signal "L3VCC")
		(2 "B.Cu" signal "BOTTOM")
		(9 "F.Adhes" user "F.Adhesive")
		(11 "B.Adhes" user "B.Adhesive")
		(13 "F.Paste" user "Package Geometry/Pastemask Top")
		(15 "B.Paste" user "Package Geometry/Pastemask Bottom")
		(5 "F.SilkS" user "Ref Des/Silkscreen Top")
		(7 "B.SilkS" user "Ref Des/Silkscreen Bottom")
		(1 "F.Mask" user "Board Geometry/Soldermask Top")
		(3 "B.Mask" user "Board Geometry/Soldermask Bottom")
		(17 "Dwgs.User" user "User.Drawings")
		(19 "Cmts.User" user "User.Comments")
		(21 "Eco1.User" user "User.Eco1")
		(23 "Eco2.User" user "User.Eco2")
		(25 "Edge.Cuts" user "Board Geometry/Outline")
		(27 "Margin" user)
		(31 "F.CrtYd" user "Package Geometry/Place Bound Top")
		(29 "B.CrtYd" user "Package Geometry/Place Bound Bottom")
		(35 "F.Fab" user "Ref Des/Assembly Top")
		(33 "B.Fab" user "Ref Des/Assembly Bottom")
	)
	(footprint ""
		(layer "F.Cu")
		(at 18.7198 -137.5664 180)
		(property "Reference" "PR104"
			(at 0 0 180)
			(layer "F.SilkS")
			(hide yes)
			(effects
				(font
					(size 1.27 1.27)
				)
			)
		)
		(property "Value" "2K7R2F-GP"
			(at 0.064008 -3.993896 180)
			(unlocked yes)
			(layer "F.Fab")
			(hide yes)
			(effects
				(font
					(size 1.016 1.016)
					(thickness 0.1524)
				)
			)
		)
		(property "Device Type" "R402H16"
			(at 0.064008 -5.517896 180)
			(unlocked yes)
			(layer "F.Fab")
			(hide yes)
			(effects
				(font
					(size 1.016 1.016)
					(thickness 0.1524)
				)
			)
		)
		(duplicate_pad_numbers_are_jumpers no)
		(fp_line
			(start 0.508 -0.9398)
			(end -0.508 -0.9398)
			(stroke
				(width 0.1524)
				(type default)
			)
			(layer "F.SilkS")
		)
		(fp_line
			(start -0.508 -0.9398)
			(end -0.508 0.9398)
			(stroke
				(width 0.1524)
				(type default)
			)
			(layer "F.SilkS")
		)
		(fp_rect
			(start -0.508 0.9398)
			(end 0.508 -0.9398)
			(stroke
				(width 0)
				(type default)
			)
			(fill no)
			(layer "F.CrtYd")
		)
		(fp_rect
			(start -0.508 0.9398)
			(end 0.508 -0.9398)
			(stroke
				(width 0)
				(type default)
			)
			(fill no)
			(layer "F.Fab")
		)
		(pad "1" smd custom
			(at 0 -0.4445 180)
			(size 0.1397 0.1397)
			(layers "F.Cu" "F.Mask" "F.Paste")
			(net "P12VU")
			(options
				(clearance outline)
				(anchor circle)
			)
			(primitives
				(gr_poly
					(pts
						(arc
							(start -0.1778 -0.2794)
							(mid -0.249642 -0.249642)
							(end -0.2794 -0.1778)
						)
						(arc
							(start -0.2794 0.1778)
							(mid -0.249642 0.249642)
							(end -0.1778 0.2794)
						)
						(arc
							(start 0.1778 0.2794)
							(mid 0.249642 0.249642)
							(end 0.2794 0.1778)
						)
						(arc
							(start 0.2794 -0.1778)
							(mid 0.249642 -0.249642)
							(end 0.1778 -0.2794)
						)
					)
					(width 0)
					(fill yes)
				)
			)
		)
		(pad "2" smd custom
			(at 0 0.4445 180)
			(size 0.1397 0.1397)
			(layers "F.Cu" "F.Mask" "F.Paste")
			(net "P12VU_2490_PG")
			(options
				(clearance outline)
				(anchor circle)
			)
			(primitives
				(gr_poly
					(pts
						(arc
							(start -0.1778 -0.2794)
							(mid -0.249642 -0.249642)
							(end -0.2794 -0.1778)
						)
						(arc
							(start -0.2794 0.1778)
							(mid -0.249642 0.249642)
							(end -0.1778 0.2794)
						)
						(arc
							(start 0.1778 0.2794)
							(mid 0.249642 0.249642)
							(end 0.2794 0.1778)
						)
						(arc
							(start 0.2794 -0.1778)
							(mid 0.249642 -0.249642)
							(end 0.1778 -0.2794)
						)
					)
					(width 0)
					(fill yes)
				)
			)
		)
	)
	(footprint ""
		(layer "F.Cu")
		(at 48.895 -111.633 90)
		(property "Reference" "PR119"
			(at 0 0 90)
			(layer "F.SilkS")
			(hide yes)
			(effects
				(font
					(size 1.27 1.27)
				)
			)
		)
		(property "Value" "10R2F-L-GP"
			(at 0.064008 -3.993896 90)
			(unlocked yes)
			(layer "F.Fab")
			(hide yes)
			(effects
				(font
					(size 1.016 1.016)
					(thickness 0.1524)
				)
			)
		)
		(property "Device Type" "R402H14"
			(at 0.064008 -5.517896 90)
			(unlocked yes)
			(layer "F.Fab")
			(hide yes)
			(effects
				(font
					(size 1.016 1.016)
					(thickness 0.1524)
				)
			)
		)
		(duplicate_pad_numbers_are_jumpers no)
		(fp_line
			(start 0.508 -0.9398)
			(end -0.508 -0.9398)
			(stroke
				(width 0.1524)
				(type default)
			)
			(layer "F.SilkS")
		)
		(fp_line
			(start -0.508 -0.9398)
			(end -0.508 0.9398)
			(stroke
				(width 0.1524)
				(type default)
			)
			(layer "F.SilkS")
		)
		(fp_rect
			(start -0.508 0.9398)
			(end 0.508 -0.9398)
			(stroke
				(width 0)
				(type default)
			)
			(fill no)
			(layer "F.CrtYd")
		)
		(fp_rect
			(start -0.508 0.9398)
			(end 0.508 -0.9398)
			(stroke
				(width 0)
				(type default)
			)
			(fill no)
			(layer "F.Fab")
		)
		(pad "1" smd custom
			(at 0 -0.4445 90)
			(size 0.1397 0.1397)
			(layers "F.Cu" "F.Mask" "F.Paste")
			(net "P12VL_2490_GATE_DRV_2")
			(options
				(clearance outline)
				(anchor circle)
			)
			(primitives
				(gr_poly
					(pts
						(arc
							(start -0.1778 -0.2794)
							(mid -0.249642 -0.249642)
							(end -0.2794 -0.1778)
						)
						(arc
							(start -0.2794 0.1778)
							(mid -0.249642 0.249642)
							(end -0.1778 0.2794)
						)
						(arc
							(start 0.1778 0.2794)
							(mid 0.249642 0.249642)
							(end 0.2794 0.1778)
						)
						(arc
							(start 0.2794 -0.1778)
							(mid 0.249642 -0.249642)
							(end 0.1778 -0.2794)
						)
					)
					(width 0)
					(fill yes)
				)
			)
		)
		(pad "2" smd custom
			(at 0 0.4445 90)
			(size 0.1397 0.1397)
			(layers "F.Cu" "F.Mask" "F.Paste")
			(net "P12VL_2490_GATE")
			(options
				(clearance outline)
				(anchor circle)
			)
			(primitives
				(gr_poly
					(pts
						(arc
							(start -0.1778 -0.2794)
							(mid -0.249642 -0.249642)
							(end -0.2794 -0.1778)
						)
						(arc
							(start -0.2794 0.1778)
							(mid -0.249642 0.249642)
							(end -0.1778 0.2794)
						)
						(arc
							(start 0.1778 0.2794)
							(mid 0.249642 0.249642)
							(end 0.2794 0.1778)
						)
						(arc
							(start 0.2794 -0.1778)
							(mid 0.249642 -0.249642)
							(end 0.1778 -0.2794)
						)
					)
					(width 0)
					(fill yes)
				)
			)
		)
	)
	(footprint ""
		(layer "F.Cu")
		(at 16.3068 -254.3302 180)
		(property "Reference" "R86"
			(at 0 0 180)
			(layer "F.SilkS")
			(hide yes)
			(effects
				(font
					(size 1.27 1.27)
				)
			)
		)
		(property "Value" "27KR3F-GP"
			(at -0.0254 -2.5146 180)
			(unlocked yes)
			(layer "F.Fab")
			(hide yes)
			(effects
				(font
					(size 1.016 1.016)
					(thickness 0.1524)
				)
			)
		)
		(property "Device Type" "R603H22"
			(at -0.0254 -4.0386 180)
			(unlocked yes)
			(layer "F.Fab")
			(hide yes)
			(effects
				(font
					(size 1.016 1.016)
					(thickness 0.1524)
				)
			)
		)
		(duplicate_pad_numbers_are_jumpers no)
		(fp_line
			(start 0.2032 0)
			(end 0.4826 0)
			(stroke
				(width 0.2032)
				(type default)
			)
			(layer "F.SilkS")
		)
		(fp_line
			(start -0.4826 0)
			(end -0.2032 0)
			(stroke
				(width 0.2032)
				(type default)
			)
			(layer "F.SilkS")
		)
		(fp_rect
			(start -0.5842 1.3335)
			(end 0.5842 -1.3335)
			(stroke
				(width 0)
				(type default)
			)
			(fill no)
			(layer "F.CrtYd")
		)
		(fp_rect
			(start -0.5842 1.3335)
			(end 0.5842 -1.3335)
			(stroke
				(width 0)
				(type default)
			)
			(fill no)
			(layer "F.Fab")
		)
		(pad "1" smd custom
			(at 0 -0.762 180)
			(size 0.2159 0.2159)
			(layers "F.Cu" "F.Mask" "F.Paste")
			(net "FANIN_5")
			(options
				(clearance outline)
				(anchor circle)
			)
			(primitives
				(gr_poly
					(pts
						(arc
							(start -0.3302 -0.4318)
							(mid -0.402042 -0.402042)
							(end -0.4318 -0.3302)
						)
						(arc
							(start -0.4318 0.3302)
							(mid -0.402042 0.402042)
							(end -0.3302 0.4318)
						)
						(arc
							(start 0.3302 0.4318)
							(mid 0.402042 0.402042)
							(end 0.4318 0.3302)
						)
						(arc
							(start 0.4318 -0.3302)
							(mid 0.402042 -0.402042)
							(end 0.3302 -0.4318)
						)
					)
					(width 0)
					(fill yes)
				)
			)
		)
		(pad "2" smd custom
			(at 0 0.762 180)
			(size 0.2159 0.2159)
			(layers "F.Cu" "F.Mask" "F.Paste")
			(net "FAN_TACH5")
			(options
				(clearance outline)
				(anchor circle)
			)
			(primitives
				(gr_poly
					(pts
						(arc
							(start -0.3302 -0.4318)
							(mid -0.402042 -0.402042)
							(end -0.4318 -0.3302)
						)
						(arc
							(start -0.4318 0.3302)
							(mid -0.402042 0.402042)
							(end -0.3302 0.4318)
						)
						(arc
							(start 0.3302 0.4318)
							(mid 0.402042 0.402042)
							(end 0.4318 0.3302)
						)
						(arc
							(start 0.4318 -0.3302)
							(mid 0.402042 -0.402042)
							(end 0.3302 -0.4318)
						)
					)
					(width 0)
					(fill yes)
				)
			)
		)
	)
	(footprint ""
		(layer "F.Cu")
		(at 9.906 -261.112 180)
		(property "Reference" "R125"
			(at 0 0 180)
			(layer "F.SilkS")
			(hide yes)
			(effects
				(font
					(size 1.27 1.27)
				)
			)
		)
		(property "Value" "1K8R6J-GP"
			(at -0.0508 -4.8514 180)
			(unlocked yes)
			(layer "F.Fab")
			(hide yes)
			(effects
				(font
					(size 1.016 1.016)
					(thickness 0.1524)
				)
			)
		)
		(property "Device Type" "R1206H28"
			(at 0 -6.3754 180)
			(unlocked yes)
			(layer "F.Fab")
			(hide yes)
			(effects
				(font
					(size 1.016 1.016)
					(thickness 0.1524)
				)
			)
		)
		(duplicate_pad_numbers_are_jumpers no)
		(fp_line
			(start 1.016 2.2352)
			(end -1.016 2.2352)
			(stroke
				(width 0.1524)
				(type default)
			)
			(layer "F.SilkS")
		)
		(fp_line
			(start 1.016 -2.2352)
			(end 1.016 2.2352)
			(stroke
				(width 0.1524)
				(type default)
			)
			(layer "F.SilkS")
		)
		(fp_line
			(start -1.016 2.2352)
			(end -1.016 -2.2352)
			(stroke
				(width 0.1524)
				(type default)
			)
			(layer "F.SilkS")
		)
		(fp_line
			(start -1.016 -2.2352)
			(end 1.016 -2.2352)
			(stroke
				(width 0.1524)
				(type default)
			)
			(layer "F.SilkS")
		)
		(fp_rect
			(start -1.0922 2.3114)
			(end 1.0922 -2.3114)
			(stroke
				(width 0)
				(type default)
			)
			(fill no)
			(layer "F.CrtYd")
		)
		(fp_poly
			(pts
				(xy -1.0922 -2.3114) (xy 1.0922 -2.3114) (xy 1.0922 2.3114) (xy -1.0922 2.3114)
			)
			(stroke
				(width 0)
				(type default)
			)
			(fill no)
			(layer "F.Fab")
		)
		(pad "1" smd rect
			(at 0 -1.397 180)
			(size 1.651 1.27)
			(layers "F.Cu" "F.Mask" "F.Paste")
			(net "P12V")
		)
		(pad "2" smd rect
			(at 0 1.397 180)
			(size 1.651 1.27)
			(layers "F.Cu" "F.Mask" "F.Paste")
			(net "LED_DR_LED2_BLUE")
		)
	)
	(footprint ""
		(layer "F.Cu")
		(at 41.3258 -136.271 90)
		(property "Reference" "PC88"
			(at 0 0 90)
			(layer "F.SilkS")
			(hide yes)
			(effects
				(font
					(size 1.27 1.27)
				)
			)
		)
		(property "Value" "SC220P50V2KX-3GP"
			(at 1.1811 -2.7051 90)
			(unlocked yes)
			(layer "F.Fab")
			(hide yes)
			(effects
				(font
					(size 1.016 1.016)
					(thickness 0.1524)
				)
			)
		)
		(property "Device Type" "C402H22"
			(at 1.1811 -4.2291 90)
			(unlocked yes)
			(layer "F.Fab")
			(hide yes)
			(effects
				(font
					(size 1.016 1.016)
					(thickness 0.1524)
				)
			)
		)
		(duplicate_pad_numbers_are_jumpers no)
		(fp_rect
			(start -0.4318 0.9525)
			(end 0.4318 -0.9525)
			(stroke
				(width 0)
				(type default)
			)
			(fill no)
			(layer "F.CrtYd")
		)
		(fp_rect
			(start -0.4318 0.9525)
			(end 0.4318 -0.9525)
			(stroke
				(width 0)
				(type default)
			)
			(fill no)
			(layer "F.Fab")
		)
		(pad "1" smd custom
			(at 0 -0.4445 90)
			(size 0.1524 0.1524)
			(layers "F.Cu" "F.Mask" "F.Paste")
			(net "P12VL_2490_SENSE")
			(options
				(clearance outline)
				(anchor circle)
			)
			(primitives
				(gr_poly
					(pts
						(arc
							(start 0.3048 -0.2032)
							(mid 0.275042 -0.275042)
							(end 0.2032 -0.3048)
						)
						(arc
							(start -0.2032 -0.3048)
							(mid -0.275042 -0.275042)
							(end -0.3048 -0.2032)
						)
						(arc
							(start -0.3048 0.2032)
							(mid -0.275042 0.275042)
							(end -0.2032 0.3048)
						)
						(arc
							(start 0.2032 0.3048)
							(mid 0.275042 0.275042)
							(end 0.3048 0.2032)
						)
					)
					(width 0)
					(fill yes)
				)
			)
		)
		(pad "2" smd custom
			(at 0 0.4445 90)
			(size 0.1524 0.1524)
			(layers "F.Cu" "F.Mask" "F.Paste")
			(net "P12VL_2490_VCC")
			(options
				(clearance outline)
				(anchor circle)
			)
			(primitives
				(gr_poly
					(pts
						(arc
							(start 0.3048 -0.2032)
							(mid 0.275042 -0.275042)
							(end 0.2032 -0.3048)
						)
						(arc
							(start -0.2032 -0.3048)
							(mid -0.275042 -0.275042)
							(end -0.3048 -0.2032)
						)
						(arc
							(start -0.3048 0.2032)
							(mid -0.275042 0.275042)
							(end -0.2032 0.3048)
						)
						(arc
							(start 0.2032 0.3048)
							(mid 0.275042 0.275042)
							(end 0.3048 0.2032)
						)
					)
					(width 0)
					(fill yes)
				)
			)
		)
	)
	(footprint ""
		(layer "F.Cu")
		(at 18.7706 -139.7254 90)
		(property "Reference" "TP23"
			(at 0 0 90)
			(layer "F.SilkS")
			(hide yes)
			(effects
				(font
					(size 1.27 1.27)
				)
			)
		)
		(property "Value" "TPAD32-GP"
			(at 0 -3.166364 90)
			(unlocked yes)
			(layer "F.Fab")
			(hide yes)
			(effects
				(font
					(size 1.016 1.016)
					(thickness 0.1524)
				)
			)
		)
		(property "Device Type" "TPAD32"
			(at 0 -4.690618 90)
			(unlocked yes)
			(layer "F.Fab")
			(hide yes)
			(effects
				(font
					(size 1.016 1.016)
					(thickness 0.1524)
				)
			)
		)
		(duplicate_pad_numbers_are_jumpers no)
		(fp_poly
			(pts
				(arc
					(start 0.7112 0)
					(mid -0.7112 0)
					(end 0.7112 0)
				)
			)
			(stroke
				(width 0)
				(type default)
			)
			(fill no)
			(layer "F.CrtYd")
		)
		(fp_poly
			(pts
				(arc
					(start 0.7112 0)
					(mid -0.7112 0)
					(end 0.7112 0)
				)
			)
			(stroke
				(width 0)
				(type default)
			)
			(fill no)
			(layer "F.Fab")
		)
		(pad "1" smd circle
			(at 0 0 90)
			(size 0.8128 0.8128)
			(layers "F.Cu" "F.Mask" "F.Paste")
			(net "P12VU_2490_PG")
		)
	)
	(footprint ""
		(layer "F.Cu")
		(at 21.844 -376.936 90)
		(property "Reference" "PR34"
			(at 0 0 90)
			(layer "F.SilkS")
			(hide yes)
			(effects
				(font
					(size 1.27 1.27)
				)
			)
		)
		(property "Value" "51KR2F-L-GP"
			(at 0.064008 -3.993896 90)
			(unlocked yes)
			(layer "F.Fab")
			(hide yes)
			(effects
				(font
					(size 1.016 1.016)
					(thickness 0.1524)
				)
			)
		)
		(property "Device Type" "R402H16"
			(at 0.064008 -5.517896 90)
			(unlocked yes)
			(layer "F.Fab")
			(hide yes)
			(effects
				(font
					(size 1.016 1.016)
					(thickness 0.1524)
				)
			)
		)
		(duplicate_pad_numbers_are_jumpers no)
		(fp_line
			(start 0.508 -0.9398)
			(end -0.508 -0.9398)
			(stroke
				(width 0.1524)
				(type default)
			)
			(layer "F.SilkS")
		)
		(fp_line
			(start -0.508 -0.9398)
			(end -0.508 0.9398)
			(stroke
				(width 0.1524)
				(type default)
			)
			(layer "F.SilkS")
		)
		(fp_rect
			(start -0.508 0.9398)
			(end 0.508 -0.9398)
			(stroke
				(width 0)
				(type default)
			)
			(fill no)
			(layer "F.CrtYd")
		)
		(fp_rect
			(start -0.508 0.9398)
			(end 0.508 -0.9398)
			(stroke
				(width 0)
				(type default)
			)
			(fill no)
			(layer "F.Fab")
		)
		(pad "1" smd custom
			(at 0 -0.4445 90)
			(size 0.1397 0.1397)
			(layers "F.Cu" "F.Mask" "F.Paste")
			(net "P12V_AUX")
			(options
				(clearance outline)
				(anchor circle)
			)
			(primitives
				(gr_poly
					(pts
						(arc
							(start -0.1778 -0.2794)
							(mid -0.249642 -0.249642)
							(end -0.2794 -0.1778)
						)
						(arc
							(start -0.2794 0.1778)
							(mid -0.249642 0.249642)
							(end -0.1778 0.2794)
						)
						(arc
							(start 0.1778 0.2794)
							(mid 0.249642 0.249642)
							(end 0.2794 0.1778)
						)
						(arc
							(start 0.2794 -0.1778)
							(mid 0.249642 -0.249642)
							(end 0.1778 -0.2794)
						)
					)
					(width 0)
					(fill yes)
				)
			)
		)
		(pad "2" smd custom
			(at 0 0.4445 90)
			(size 0.1397 0.1397)
			(layers "F.Cu" "F.Mask" "F.Paste")
			(net "ADM1276_UV")
			(options
				(clearance outline)
				(anchor circle)
			)
			(primitives
				(gr_poly
					(pts
						(arc
							(start -0.1778 -0.2794)
							(mid -0.249642 -0.249642)
							(end -0.2794 -0.1778)
						)
						(arc
							(start -0.2794 0.1778)
							(mid -0.249642 0.249642)
							(end -0.1778 0.2794)
						)
						(arc
							(start 0.1778 0.2794)
							(mid 0.249642 0.249642)
							(end 0.2794 0.1778)
						)
						(arc
							(start 0.2794 -0.1778)
							(mid 0.249642 -0.249642)
							(end 0.1778 -0.2794)
						)
					)
					(width 0)
					(fill yes)
				)
			)
		)
	)
	(footprint ""
		(layer "F.Cu")
		(at 23.622 -363.601 -90)
		(property "Reference" "PC5"
			(at 0 0 270)
			(layer "F.SilkS")
			(hide yes)
			(effects
				(font
					(size 1.27 1.27)
				)
			)
		)
		(property "Value" "SCD01U25V2KX-3GP"
			(at 1.1811 -2.7051 270)
			(unlocked yes)
			(layer "F.Fab")
			(hide yes)
			(effects
				(font
					(size 1.016 1.016)
					(thickness 0.1524)
				)
			)
		)
		(property "Device Type" "C402H22"
			(at 1.1811 -4.2291 270)
			(unlocked yes)
			(layer "F.Fab")
			(hide yes)
			(effects
				(font
					(size 1.016 1.016)
					(thickness 0.1524)
				)
			)
		)
		(duplicate_pad_numbers_are_jumpers no)
		(fp_rect
			(start -0.4318 0.9525)
			(end 0.4318 -0.9525)
			(stroke
				(width 0)
				(type default)
			)
			(fill no)
			(layer "F.CrtYd")
		)
		(fp_rect
			(start -0.4318 0.9525)
			(end 0.4318 -0.9525)
			(stroke
				(width 0)
				(type default)
			)
			(fill no)
			(layer "F.Fab")
		)
		(pad "1" smd custom
			(at 0 -0.4445 270)
			(size 0.1524 0.1524)
			(layers "F.Cu" "F.Mask" "F.Paste")
			(net "ADM1276_TIMER")
			(options
				(clearance outline)
				(anchor circle)
			)
			(primitives
				(gr_poly
					(pts
						(arc
							(start 0.3048 -0.2032)
							(mid 0.275042 -0.275042)
							(end 0.2032 -0.3048)
						)
						(arc
							(start -0.2032 -0.3048)
							(mid -0.275042 -0.275042)
							(end -0.3048 -0.2032)
						)
						(arc
							(start -0.3048 0.2032)
							(mid -0.275042 0.275042)
							(end -0.2032 0.3048)
						)
						(arc
							(start 0.2032 0.3048)
							(mid 0.275042 0.275042)
							(end 0.3048 0.2032)
						)
					)
					(width 0)
					(fill yes)
				)
			)
		)
		(pad "2" smd custom
			(at 0 0.4445 270)
			(size 0.1524 0.1524)
			(layers "F.Cu" "F.Mask" "F.Paste")
			(net "GND")
			(options
				(clearance outline)
				(anchor circle)
			)
			(primitives
				(gr_poly
					(pts
						(arc
							(start 0.3048 -0.2032)
							(mid 0.275042 -0.275042)
							(end 0.2032 -0.3048)
						)
						(arc
							(start -0.2032 -0.3048)
							(mid -0.275042 -0.275042)
							(end -0.3048 -0.2032)
						)
						(arc
							(start -0.3048 0.2032)
							(mid -0.275042 0.275042)
							(end -0.2032 0.3048)
						)
						(arc
							(start 0.2032 0.3048)
							(mid 0.275042 0.275042)
							(end 0.3048 0.2032)
						)
					)
					(width 0)
					(fill yes)
				)
			)
		)
	)
)
